# T6G (Grand Teton) — schematic netlist excerpt (pin names and nets, part order shuffled) for the footprints in the layout excerpt that follows; sources: Cadence DE-HDL packaged netlist, KiCad conversion of 04192023_DAF0TMB3IC0_F0TG_MB_C_brd_V02_OCP.brd

PC6618  Q_CAP  22UF 16V 20% X6S  pkg C0805  page 365 : A = SW_P12V_AUX_P0V9_RETIMER_CPU1_FLT ; B = GND
R5030  Q_RES  4.7K 5% EMPTY  pkg 0402LF  page 55 : A = GND ; B = FM_BMC_TPM_PRES_N
R147  Q_RES  0 5% EMPTY  pkg 0402LF  page 161 : A = SMB_CPU0_CPU1_APML_MUX1_SDA ; B = SMB_APML_CPU1_R_SDA

(kicad_pcb
	(version 20260206)
	(generator "pcbnew")
	(generator_version "10.0")
	(general
		(thickness 1.6)
		(legacy_teardrops no)
	)
	(paper "A4")
	(title_block
		(title "04192023_DAF0TMB3IC0_F0TG_MB_C_brd_V02_OCP.brd")
		(comment 1 "Grand Teton / footprints 7686-7688 of 8354")
	)
	(layers
		(0 "F.Cu" signal "TOP")
		(4 "In1.Cu" signal "GND")
		(6 "In2.Cu" signal "IN1")
		(8 "In3.Cu" signal "GND1")
		(10 "In4.Cu" signal "IN2")
		(12 "In5.Cu" signal "GND2")
		(14 "In6.Cu" signal "IN3")
		(16 "In7.Cu" signal "GND3")
		(18 "In8.Cu" signal "VCC")
		(20 "In9.Cu" signal "VCC1")
		(22 "In10.Cu" signal "GND4")
		(24 "In11.Cu" signal "IN4")
		(26 "In12.Cu" signal "GND5")
		(28 "In13.Cu" signal "IN5")
		(30 "In14.Cu" signal "GND6")
		(32 "In15.Cu" signal "IN6")
		(34 "In16.Cu" signal "GND7")
		(2 "B.Cu" signal "BOTTOM")
		(9 "F.Adhes" user "F.Adhesive")
		(11 "B.Adhes" user "B.Adhesive")
		(13 "F.Paste" user "Package Geometry/Pastemask Top")
		(15 "B.Paste" user "Package Geometry/Pastemask Bottom")
		(5 "F.SilkS" user "Ref Des/Silkscreen Top")
		(7 "B.SilkS" user "Ref Des/Silkscreen Bottom")
		(1 "F.Mask" user "Board Geometry/Soldermask Top")
		(3 "B.Mask" user "Board Geometry/Soldermask Bottom")
		(17 "Dwgs.User" user "User.Drawings")
		(19 "Cmts.User" user "User.Comments")
		(21 "Eco1.User" user "User.Eco1")
		(23 "Eco2.User" user "User.Eco2")
		(25 "Edge.Cuts" user "Board Geometry/Outline")
		(27 "Margin" user)
		(31 "F.CrtYd" user "Package Geometry/Place Bound Top")
		(29 "B.CrtYd" user "Package Geometry/Place Bound Bottom")
		(35 "F.Fab" user "Ref Des/Assembly Top")
		(33 "B.Fab" user "Ref Des/Assembly Bottom")
	)
	(footprint ""
		(layer "B.Cu")
		(at 228.854 -232.156 -90)
		(property "Reference" "R147"
			(at 0 0 90)
			(layer "B.SilkS")
			(hide yes)
			(effects
				(font
					(size 1.27 1.27)
				)
				(justify mirror)
			)
		)
		(property "Value" ""
			(at 0 0 90)
			(layer "B.Fab")
			(effects
				(font
					(size 1.27 1.27)
				)
				(justify mirror)
			)
		)
		(duplicate_pad_numbers_are_jumpers no)
		(fp_line
			(start -0.7874 0.4064)
			(end 0.7874 0.4064)
			(stroke
				(width 0.1524)
				(type default)
			)
			(layer "B.SilkS")
		)
		(fp_line
			(start 0.7874 0.4064)
			(end 0.7874 -0.4064)
			(stroke
				(width 0.1524)
				(type default)
			)
			(layer "B.SilkS")
		)
		(fp_line
			(start -0.7874 -0.4064)
			(end -0.7874 0.4064)
			(stroke
				(width 0.1524)
				(type default)
			)
			(layer "B.SilkS")
		)
		(fp_line
			(start 0.7874 -0.4064)
			(end -0.7874 -0.4064)
			(stroke
				(width 0.1524)
				(type default)
			)
			(layer "B.SilkS")
		)
		(fp_line
			(start -0.67945 0.3048)
			(end -0.120396 0.3048)
			(stroke
				(width 0.1)
				(type default)
			)
			(layer "B.Fab")
		)
		(fp_line
			(start -0.120396 0.3048)
			(end -0.120396 0.2794)
			(stroke
				(width 0.1)
				(type default)
			)
			(layer "B.Fab")
		)
		(fp_line
			(start 0.12065 0.3048)
			(end 0.67945 0.3048)
			(stroke
				(width 0.1)
				(type default)
			)
			(layer "B.Fab")
		)
		(fp_line
			(start 0.67945 0.3048)
			(end 0.67945 -0.305054)
			(stroke
				(width 0.1)
				(type default)
			)
			(layer "B.Fab")
		)
		(fp_line
			(start -0.120396 0.2794)
			(end 0.12065 0.2794)
			(stroke
				(width 0.1)
				(type default)
			)
			(layer "B.Fab")
		)
		(fp_line
			(start 0.12065 0.2794)
			(end 0.12065 0.3048)
			(stroke
				(width 0.1)
				(type default)
			)
			(layer "B.Fab")
		)
		(fp_line
			(start -0.12065 -0.2794)
			(end -0.12065 -0.3048)
			(stroke
				(width 0.1)
				(type default)
			)
			(layer "B.Fab")
		)
		(fp_line
			(start 0.12065 -0.2794)
			(end -0.12065 -0.2794)
			(stroke
				(width 0.1)
				(type default)
			)
			(layer "B.Fab")
		)
		(fp_line
			(start -0.67945 -0.3048)
			(end -0.67945 0.3048)
			(stroke
				(width 0.1)
				(type default)
			)
			(layer "B.Fab")
		)
		(fp_line
			(start -0.12065 -0.3048)
			(end -0.67945 -0.3048)
			(stroke
				(width 0.1)
				(type default)
			)
			(layer "B.Fab")
		)
		(fp_line
			(start 0.12065 -0.305054)
			(end 0.12065 -0.2794)
			(stroke
				(width 0.1)
				(type default)
			)
			(layer "B.Fab")
		)
		(fp_line
			(start 0.67945 -0.305054)
			(end 0.12065 -0.305054)
			(stroke
				(width 0.1)
				(type default)
			)
			(layer "B.Fab")
		)
		(pad "1" smd circle
			(at 0.40005 0 90)
			(size 0 0)
			(layers "B.Cu" "B.Mask" "B.Paste")
			(net "SMB_CPU0_CPU1_APML_MUX1_SDA")
		)
		(pad "2" smd circle
			(at -0.40005 0 90)
			(size 0 0)
			(layers "B.Cu" "B.Mask" "B.Paste")
			(net "SMB_APML_CPU1_R_SDA")
		)
	)
	(footprint ""
		(layer "B.Cu")
		(at 143.04137 -316.465458 180)
		(property "Reference" "R5030"
			(at 0 0 0)
			(layer "B.SilkS")
			(hide yes)
			(effects
				(font
					(size 1.27 1.27)
				)
				(justify mirror)
			)
		)
		(property "Value" ""
			(at 0 0 0)
			(layer "B.Fab")
			(effects
				(font
					(size 1.27 1.27)
				)
				(justify mirror)
			)
		)
		(duplicate_pad_numbers_are_jumpers no)
		(fp_line
			(start 0.7874 0.4064)
			(end 0.7874 -0.4064)
			(stroke
				(width 0.1524)
				(type default)
			)
			(layer "B.SilkS")
		)
		(fp_line
			(start 0.7874 -0.4064)
			(end -0.7874 -0.4064)
			(stroke
				(width 0.1524)
				(type default)
			)
			(layer "B.SilkS")
		)
		(fp_line
			(start -0.7874 0.4064)
			(end 0.7874 0.4064)
			(stroke
				(width 0.1524)
				(type default)
			)
			(layer "B.SilkS")
		)
		(fp_line
			(start -0.7874 -0.4064)
			(end -0.7874 0.4064)
			(stroke
				(width 0.1524)
				(type default)
			)
			(layer "B.SilkS")
		)
		(fp_line
			(start 0.67945 0.3048)
			(end 0.67945 -0.305054)
			(stroke
				(width 0.1)
				(type default)
			)
			(layer "B.Fab")
		)
		(fp_line
			(start 0.67945 -0.305054)
			(end 0.12065 -0.305054)
			(stroke
				(width 0.1)
				(type default)
			)
			(layer "B.Fab")
		)
		(fp_line
			(start 0.12065 0.3048)
			(end 0.67945 0.3048)
			(stroke
				(width 0.1)
				(type default)
			)
			(layer "B.Fab")
		)
		(fp_line
			(start 0.12065 0.2794)
			(end 0.12065 0.3048)
			(stroke
				(width 0.1)
				(type default)
			)
			(layer "B.Fab")
		)
		(fp_line
			(start 0.12065 -0.2794)
			(end -0.12065 -0.2794)
			(stroke
				(width 0.1)
				(type default)
			)
			(layer "B.Fab")
		)
		(fp_line
			(start 0.12065 -0.305054)
			(end 0.12065 -0.2794)
			(stroke
				(width 0.1)
				(type default)
			)
			(layer "B.Fab")
		)
		(fp_line
			(start -0.120396 0.3048)
			(end -0.120396 0.2794)
			(stroke
				(width 0.1)
				(type default)
			)
			(layer "B.Fab")
		)
		(fp_line
			(start -0.120396 0.2794)
			(end 0.12065 0.2794)
			(stroke
				(width 0.1)
				(type default)
			)
			(layer "B.Fab")
		)
		(fp_line
			(start -0.12065 -0.2794)
			(end -0.12065 -0.3048)
			(stroke
				(width 0.1)
				(type default)
			)
			(layer "B.Fab")
		)
		(fp_line
			(start -0.12065 -0.3048)
			(end -0.67945 -0.3048)
			(stroke
				(width 0.1)
				(type default)
			)
			(layer "B.Fab")
		)
		(fp_line
			(start -0.67945 0.3048)
			(end -0.120396 0.3048)
			(stroke
				(width 0.1)
				(type default)
			)
			(layer "B.Fab")
		)
		(fp_line
			(start -0.67945 -0.3048)
			(end -0.67945 0.3048)
			(stroke
				(width 0.1)
				(type default)
			)
			(layer "B.Fab")
		)
		(pad "1" smd circle
			(at 0.40005 0)
			(size 0 0)
			(layers "B.Cu" "B.Mask" "B.Paste")
			(net "GND")
		)
		(pad "2" smd circle
			(at -0.40005 0)
			(size 0 0)
			(layers "B.Cu" "B.Mask" "B.Paste")
			(net "FM_BMC_TPM_PRES_N")
		)
	)
	(footprint ""
		(layer "B.Cu")
		(at 18.039588 -395.703806)
		(property "Reference" "PC6618"
			(at 0 0 0)
			(layer "B.SilkS")
			(hide yes)
			(effects
				(font
					(size 1.27 1.27)
				)
				(justify mirror)
			)
		)
		(property "Value" ""
			(at 0 0 0)
			(layer "B.Fab")
			(effects
				(font
					(size 1.27 1.27)
				)
				(justify mirror)
			)
		)
		(duplicate_pad_numbers_are_jumpers no)
		(fp_line
			(start -1.524 -0.762)
			(end -1.524 0.762)
			(stroke
				(width 0.1524)
				(type default)
			)
			(layer "B.SilkS")
		)
		(fp_line
			(start -1.524 0.762)
			(end 1.524 0.762)
			(stroke
				(width 0.1524)
				(type default)
			)
			(layer "B.SilkS")
		)
		(fp_line
			(start 1.524 -0.762)
			(end -1.524 -0.762)
			(stroke
				(width 0.1524)
				(type default)
			)
			(layer "B.SilkS")
		)
		(fp_line
			(start 1.524 0.762)
			(end 1.524 -0.762)
			(stroke
				(width 0.1524)
				(type default)
			)
			(layer "B.SilkS")
		)
		(fp_line
			(start -1.1049 -0.724916)
			(end 1.1049 -0.724916)
			(stroke
				(width 0.1)
				(type default)
			)
			(layer "B.Fab")
		)
		(fp_line
			(start -1.1049 0.724916)
			(end -1.1049 -0.724916)
			(stroke
				(width 0.1)
				(type default)
			)
			(layer "B.Fab")
		)
		(fp_line
			(start 1.1049 -0.724916)
			(end 1.1049 0.724916)
			(stroke
				(width 0.1)
				(type default)
			)
			(layer "B.Fab")
		)
		(fp_line
			(start 1.1049 0.724916)
			(end -1.1049 0.724916)
			(stroke
				(width 0.1)
				(type default)
			)
			(layer "B.Fab")
		)
		(pad "1" smd rect
			(at 0.889 0)
			(size 1.016 1.27)
			(layers "B.Cu" "B.Mask" "B.Paste")
			(net "SW_P12V_AUX_P0V9_RETIMER_CPU1_FLT")
		)
		(pad "2" smd rect
			(at -0.889 0)
			(size 1.016 1.27)
			(layers "B.Cu" "B.Mask" "B.Paste")
			(net "GND")
		)
	)
)
